(kicad_pcb
	(version 20260206)
	(generator "pcbnew")
	(generator_version "10.0")
	(general
		(thickness 1.6)
		(legacy_teardrops no)
	)
	(paper "A4")
	(title_block
		(title "03242023_DA0F0TMBIJ0_F0T_Motherboard_J_brd_V01_OCP.brd")
		(comment 1 "Grand Teton / footprints 1691-1696 of 6105")
	)
	(layers
		(0 "F.Cu" signal "TOP")
		(4 "In1.Cu" signal "GND")
		(6 "In2.Cu" signal "IN1")
		(8 "In3.Cu" signal "GND1")
		(10 "In4.Cu" signal "IN2")
		(12 "In5.Cu" signal "GND2")
		(14 "In6.Cu" signal "IN3")
		(16 "In7.Cu" signal "GND3")
		(18 "In8.Cu" signal "VCC")
		(20 "In9.Cu" signal "VCC1")
		(22 "In10.Cu" signal "GND4")
		(24 "In11.Cu" signal "IN4")
		(26 "In12.Cu" signal "GND5")
		(28 "In13.Cu" signal "IN5")
		(30 "In14.Cu" signal "GND6")
		(32 "In15.Cu" signal "IN6")
		(34 "In16.Cu" signal "GND7")
		(2 "B.Cu" signal "BOTTOM")
		(9 "F.Adhes" user "F.Adhesive")
		(11 "B.Adhes" user "B.Adhesive")
		(13 "F.Paste" user "Package Geometry/Pastemask Top")
		(15 "B.Paste" user "Package Geometry/Pastemask Bottom")
		(5 "F.SilkS" user "Ref Des/Silkscreen Top")
		(7 "B.SilkS" user "Ref Des/Silkscreen Bottom")
		(1 "F.Mask" user "Board Geometry/Soldermask Top")
		(3 "B.Mask" user "Board Geometry/Soldermask Bottom")
		(17 "Dwgs.User" user "User.Drawings")
		(19 "Cmts.User" user "User.Comments")
		(21 "Eco1.User" user "User.Eco1")
		(23 "Eco2.User" user "User.Eco2")
		(25 "Edge.Cuts" user "Board Geometry/Outline")
		(27 "Margin" user)
		(31 "F.CrtYd" user "Package Geometry/Place Bound Top")
		(29 "B.CrtYd" user "Package Geometry/Place Bound Bottom")
		(35 "F.Fab" user "Ref Des/Assembly Top")
		(33 "B.Fab" user "Ref Des/Assembly Bottom")
	)
	(footprint ""
		(layer "F.Cu")
		(at 150.83028 -34.623756 180)
		(property "Reference" "R3304"
			(at 0 0 180)
			(layer "F.SilkS")
			(hide yes)
			(effects
				(font
					(size 1.27 1.27)
				)
			)
		)
		(property "Value" ""
			(at 0 0 180)
			(layer "F.Fab")
			(effects
				(font
					(size 1.27 1.27)
				)
			)
		)
		(duplicate_pad_numbers_are_jumpers no)
		(fp_line
			(start 0.7874 0.4064)
			(end -0.7874 0.4064)
			(stroke
				(width 0.1524)
				(type default)
			)
			(layer "F.SilkS")
		)
		(fp_line
			(start 0.7874 -0.4064)
			(end 0.7874 0.4064)
			(stroke
				(width 0.1524)
				(type default)
			)
			(layer "F.SilkS")
		)
		(fp_line
			(start -0.7874 0.4064)
			(end -0.7874 -0.4064)
			(stroke
				(width 0.1524)
				(type default)
			)
			(layer "F.SilkS")
		)
		(fp_line
			(start -0.7874 -0.4064)
			(end 0.7874 -0.4064)
			(stroke
				(width 0.1524)
				(type default)
			)
			(layer "F.SilkS")
		)
		(fp_line
			(start 0.67945 0.3048)
			(end 0.120396 0.3048)
			(stroke
				(width 0.1)
				(type default)
			)
			(layer "F.Fab")
		)
		(fp_line
			(start 0.67945 -0.3048)
			(end 0.67945 0.3048)
			(stroke
				(width 0.1)
				(type default)
			)
			(layer "F.Fab")
		)
		(fp_line
			(start 0.12065 -0.2794)
			(end 0.12065 -0.3048)
			(stroke
				(width 0.1)
				(type default)
			)
			(layer "F.Fab")
		)
		(fp_line
			(start 0.12065 -0.3048)
			(end 0.67945 -0.3048)
			(stroke
				(width 0.1)
				(type default)
			)
			(layer "F.Fab")
		)
		(fp_line
			(start 0.120396 0.3048)
			(end 0.120396 0.2794)
			(stroke
				(width 0.1)
				(type default)
			)
			(layer "F.Fab")
		)
		(fp_line
			(start 0.120396 0.2794)
			(end -0.12065 0.2794)
			(stroke
				(width 0.1)
				(type default)
			)
			(layer "F.Fab")
		)
		(fp_line
			(start -0.12065 0.3048)
			(end -0.67945 0.3048)
			(stroke
				(width 0.1)
				(type default)
			)
			(layer "F.Fab")
		)
		(fp_line
			(start -0.12065 0.2794)
			(end -0.12065 0.3048)
			(stroke
				(width 0.1)
				(type default)
			)
			(layer "F.Fab")
		)
		(fp_line
			(start -0.12065 -0.2794)
			(end 0.12065 -0.2794)
			(stroke
				(width 0.1)
				(type default)
			)
			(layer "F.Fab")
		)
		(fp_line
			(start -0.12065 -0.305054)
			(end -0.12065 -0.2794)
			(stroke
				(width 0.1)
				(type default)
			)
			(layer "F.Fab")
		)
		(fp_line
			(start -0.67945 0.3048)
			(end -0.67945 -0.305054)
			(stroke
				(width 0.1)
				(type default)
			)
			(layer "F.Fab")
		)
		(fp_line
			(start -0.67945 -0.305054)
			(end -0.12065 -0.305054)
			(stroke
				(width 0.1)
				(type default)
			)
			(layer "F.Fab")
		)
		(pad "1" smd circle
			(at -0.40005 0 180)
			(size 0 0)
			(layers "F.Cu" "F.Mask" "F.Paste")
			(net "OCP_SFF_PRSNT_ALL_R_N")
		)
		(pad "2" smd circle
			(at 0.40005 0 180)
			(size 0 0)
			(layers "F.Cu" "F.Mask" "F.Paste")
			(net "OCP_SFF_PRSNT_ALL_R3_N")
		)
	)
	(footprint ""
		(layer "F.Cu")
		(at 32.780478 -437.688228 180)
		(property "Reference" "R2991"
			(at 0 0 180)
			(layer "F.SilkS")
			(hide yes)
			(effects
				(font
					(size 1.27 1.27)
				)
			)
		)
		(property "Value" ""
			(at 0 0 180)
			(layer "F.Fab")
			(effects
				(font
					(size 1.27 1.27)
				)
			)
		)
		(duplicate_pad_numbers_are_jumpers no)
		(fp_line
			(start 0.7874 0.4064)
			(end -0.7874 0.4064)
			(stroke
				(width 0.1524)
				(type default)
			)
			(layer "F.SilkS")
		)
		(fp_line
			(start 0.7874 -0.4064)
			(end 0.7874 0.4064)
			(stroke
				(width 0.1524)
				(type default)
			)
			(layer "F.SilkS")
		)
		(fp_line
			(start -0.7874 0.4064)
			(end -0.7874 -0.4064)
			(stroke
				(width 0.1524)
				(type default)
			)
			(layer "F.SilkS")
		)
		(fp_line
			(start -0.7874 -0.4064)
			(end 0.7874 -0.4064)
			(stroke
				(width 0.1524)
				(type default)
			)
			(layer "F.SilkS")
		)
		(fp_line
			(start 0.67945 0.3048)
			(end 0.120396 0.3048)
			(stroke
				(width 0.1)
				(type default)
			)
			(layer "F.Fab")
		)
		(fp_line
			(start 0.67945 -0.3048)
			(end 0.67945 0.3048)
			(stroke
				(width 0.1)
				(type default)
			)
			(layer "F.Fab")
		)
		(fp_line
			(start 0.12065 -0.2794)
			(end 0.12065 -0.3048)
			(stroke
				(width 0.1)
				(type default)
			)
			(layer "F.Fab")
		)
		(fp_line
			(start 0.12065 -0.3048)
			(end 0.67945 -0.3048)
			(stroke
				(width 0.1)
				(type default)
			)
			(layer "F.Fab")
		)
		(fp_line
			(start 0.120396 0.3048)
			(end 0.120396 0.2794)
			(stroke
				(width 0.1)
				(type default)
			)
			(layer "F.Fab")
		)
		(fp_line
			(start 0.120396 0.2794)
			(end -0.12065 0.2794)
			(stroke
				(width 0.1)
				(type default)
			)
			(layer "F.Fab")
		)
		(fp_line
			(start -0.12065 0.3048)
			(end -0.67945 0.3048)
			(stroke
				(width 0.1)
				(type default)
			)
			(layer "F.Fab")
		)
		(fp_line
			(start -0.12065 0.2794)
			(end -0.12065 0.3048)
			(stroke
				(width 0.1)
				(type default)
			)
			(layer "F.Fab")
		)
		(fp_line
			(start -0.12065 -0.2794)
			(end 0.12065 -0.2794)
			(stroke
				(width 0.1)
				(type default)
			)
			(layer "F.Fab")
		)
		(fp_line
			(start -0.12065 -0.305054)
			(end -0.12065 -0.2794)
			(stroke
				(width 0.1)
				(type default)
			)
			(layer "F.Fab")
		)
		(fp_line
			(start -0.67945 0.3048)
			(end -0.67945 -0.305054)
			(stroke
				(width 0.1)
				(type default)
			)
			(layer "F.Fab")
		)
		(fp_line
			(start -0.67945 -0.305054)
			(end -0.12065 -0.305054)
			(stroke
				(width 0.1)
				(type default)
			)
			(layer "F.Fab")
		)
		(pad "1" smd circle
			(at -0.40005 0 180)
			(size 0 0)
			(layers "F.Cu" "F.Mask" "F.Paste")
			(net "SMB_2_BMC_GPU_BUF_R_SDA")
		)
		(pad "2" smd circle
			(at 0.40005 0 180)
			(size 0 0)
			(layers "F.Cu" "F.Mask" "F.Paste")
			(net "SMB_2_BMC_GPU_BUF_SDA")
		)
	)
	(footprint ""
		(layer "F.Cu")
		(at 447.482214 -117.193822)
		(property "Reference" "R1123"
			(at 0 0 0)
			(layer "F.SilkS")
			(hide yes)
			(effects
				(font
					(size 1.27 1.27)
				)
			)
		)
		(property "Value" ""
			(at 0 0 0)
			(layer "F.Fab")
			(effects
				(font
					(size 1.27 1.27)
				)
			)
		)
		(duplicate_pad_numbers_are_jumpers no)
		(fp_line
			(start -0.7874 -0.4064)
			(end 0.7874 -0.4064)
			(stroke
				(width 0.1524)
				(type default)
			)
			(layer "F.SilkS")
		)
		(fp_line
			(start -0.7874 0.4064)
			(end -0.7874 -0.4064)
			(stroke
				(width 0.1524)
				(type default)
			)
			(layer "F.SilkS")
		)
		(fp_line
			(start 0.7874 -0.4064)
			(end 0.7874 0.4064)
			(stroke
				(width 0.1524)
				(type default)
			)
			(layer "F.SilkS")
		)
		(fp_line
			(start 0.7874 0.4064)
			(end -0.7874 0.4064)
			(stroke
				(width 0.1524)
				(type default)
			)
			(layer "F.SilkS")
		)
		(fp_line
			(start -0.67945 -0.305054)
			(end -0.12065 -0.305054)
			(stroke
				(width 0.1)
				(type default)
			)
			(layer "F.Fab")
		)
		(fp_line
			(start -0.67945 0.3048)
			(end -0.67945 -0.305054)
			(stroke
				(width 0.1)
				(type default)
			)
			(layer "F.Fab")
		)
		(fp_line
			(start -0.12065 -0.305054)
			(end -0.12065 -0.2794)
			(stroke
				(width 0.1)
				(type default)
			)
			(layer "F.Fab")
		)
		(fp_line
			(start -0.12065 -0.2794)
			(end 0.12065 -0.2794)
			(stroke
				(width 0.1)
				(type default)
			)
			(layer "F.Fab")
		)
		(fp_line
			(start -0.12065 0.2794)
			(end -0.12065 0.3048)
			(stroke
				(width 0.1)
				(type default)
			)
			(layer "F.Fab")
		)
		(fp_line
			(start -0.12065 0.3048)
			(end -0.67945 0.3048)
			(stroke
				(width 0.1)
				(type default)
			)
			(layer "F.Fab")
		)
		(fp_line
			(start 0.120396 0.2794)
			(end -0.12065 0.2794)
			(stroke
				(width 0.1)
				(type default)
			)
			(layer "F.Fab")
		)
		(fp_line
			(start 0.120396 0.3048)
			(end 0.120396 0.2794)
			(stroke
				(width 0.1)
				(type default)
			)
			(layer "F.Fab")
		)
		(fp_line
			(start 0.12065 -0.3048)
			(end 0.67945 -0.3048)
			(stroke
				(width 0.1)
				(type default)
			)
			(layer "F.Fab")
		)
		(fp_line
			(start 0.12065 -0.2794)
			(end 0.12065 -0.3048)
			(stroke
				(width 0.1)
				(type default)
			)
			(layer "F.Fab")
		)
		(fp_line
			(start 0.67945 -0.3048)
			(end 0.67945 0.3048)
			(stroke
				(width 0.1)
				(type default)
			)
			(layer "F.Fab")
		)
		(fp_line
			(start 0.67945 0.3048)
			(end 0.120396 0.3048)
			(stroke
				(width 0.1)
				(type default)
			)
			(layer "F.Fab")
		)
		(pad "1" smd circle
			(at -0.40005 0)
			(size 0 0)
			(layers "F.Cu" "F.Mask" "F.Paste")
			(net "P3V3_AUX")
		)
		(pad "2" smd circle
			(at 0.40005 0)
			(size 0 0)
			(layers "F.Cu" "F.Mask" "F.Paste")
			(net "PD_SMB_OCP1_HP_ADD2")
		)
	)
	(footprint ""
		(layer "F.Cu")
		(at 428.179992 -391.505948)
		(property "Reference" "Q70"
			(at 0.462788 -1.93675 0)
			(unlocked yes)
			(layer "F.SilkS")
			(effects
				(font
					(size 0.7874 0.5842)
					(thickness 0.1524)
				)
				(justify left)
			)
		)
		(property "Value" ""
			(at 0 0 0)
			(layer "F.Fab")
			(effects
				(font
					(size 1.27 1.27)
				)
			)
		)
		(duplicate_pad_numbers_are_jumpers no)
		(fp_line
			(start -1.332738 -1.100074)
			(end -0.4826 -1.100074)
			(stroke
				(width 0.1524)
				(type default)
			)
			(layer "F.SilkS")
		)
		(fp_line
			(start -1.332738 1.100074)
			(end -1.332738 -1.100074)
			(stroke
				(width 0.1524)
				(type default)
			)
			(layer "F.SilkS")
		)
		(fp_line
			(start -0.4826 -1.100074)
			(end 0 -0.541274)
			(stroke
				(width 0.1524)
				(type default)
			)
			(layer "F.SilkS")
		)
		(fp_line
			(start 0 -0.541274)
			(end 0.4826 -1.100074)
			(stroke
				(width 0.1524)
				(type default)
			)
			(layer "F.SilkS")
		)
		(fp_line
			(start 0.4826 -1.100074)
			(end 1.332738 -1.100074)
			(stroke
				(width 0.1524)
				(type default)
			)
			(layer "F.SilkS")
		)
		(fp_line
			(start 1.332738 -1.100074)
			(end 1.332738 1.100074)
			(stroke
				(width 0.1524)
				(type default)
			)
			(layer "F.SilkS")
		)
		(fp_line
			(start 1.332738 1.100074)
			(end -1.332738 1.100074)
			(stroke
				(width 0.1524)
				(type default)
			)
			(layer "F.SilkS")
		)
		(fp_poly
			(pts
				(xy -0.613918 -2.146808) (xy -0.964946 -1.444752) (xy -1.315974 -2.146808)
			)
			(stroke
				(width 0)
				(type default)
			)
			(fill yes)
			(layer "F.SilkS")
		)
		(fp_line
			(start -0.674878 -1.100074)
			(end 0.674878 -1.100074)
			(stroke
				(width 0.1)
				(type default)
			)
			(layer "F.Fab")
		)
		(fp_line
			(start -0.674878 1.100074)
			(end -0.674878 -1.100074)
			(stroke
				(width 0.1)
				(type default)
			)
			(layer "F.Fab")
		)
		(fp_line
			(start 0.674878 -1.100074)
			(end 0.674878 1.100074)
			(stroke
				(width 0.1)
				(type default)
			)
			(layer "F.Fab")
		)
		(fp_line
			(start 0.674878 1.100074)
			(end -0.674878 1.100074)
			(stroke
				(width 0.1)
				(type default)
			)
			(layer "F.Fab")
		)
		(fp_poly
			(pts
				(xy -2.2352 -0.298958) (xy -2.2352 -1.001014) (xy -1.533144 -0.649986)
			)
			(stroke
				(width 0)
				(type default)
			)
			(fill yes)
			(layer "F.Fab")
		)
		(pad "1" smd rect
			(at -0.94996 -0.649986 90)
			(size 0.4318 0.508)
			(layers "F.Cu" "F.Mask" "F.Paste")
			(net "GND")
		)
		(pad "2" smd rect
			(at -0.94996 0 90)
			(size 0.4318 0.508)
			(layers "F.Cu" "F.Mask" "F.Paste")
			(net "FM_SWB_BIC_READY_N")
		)
		(pad "3" smd rect
			(at -0.94996 0.649986 90)
			(size 0.4318 0.508)
			(layers "F.Cu" "F.Mask" "F.Paste")
			(net "FM_SWB_BIC_READY_ISO_N")
		)
		(pad "4" smd rect
			(at 0.94996 0.649986 90)
			(size 0.4318 0.508)
			(layers "F.Cu" "F.Mask" "F.Paste")
			(net "GND")
		)
		(pad "5" smd rect
			(at 0.94996 0 90)
			(size 0.4318 0.508)
			(layers "F.Cu" "F.Mask" "F.Paste")
			(net "FM_SWB_BIC_READY")
		)
		(pad "6" smd rect
			(at 0.94996 -0.649986 90)
			(size 0.4318 0.508)
			(layers "F.Cu" "F.Mask" "F.Paste")
			(net "FM_SWB_BIC_READY")
		)
	)
	(footprint ""
		(layer "F.Cu")
		(at 116.13388 -407.16073 -90)
		(property "Reference" "Q67"
			(at 0.973836 1.916176 90)
			(unlocked yes)
			(layer "F.SilkS")
			(effects
				(font
					(size 0.7874 0.5842)
					(thickness 0.1524)
				)
				(justify left)
			)
		)
		(property "Value" ""
			(at 0 0 270)
			(layer "F.Fab")
			(effects
				(font
					(size 1.27 1.27)
				)
			)
		)
		(duplicate_pad_numbers_are_jumpers no)
		(fp_line
			(start -1.332738 1.100074)
			(end -1.332738 -1.100074)
			(stroke
				(width 0.1524)
				(type default)
			)
			(layer "F.SilkS")
		)
		(fp_line
			(start 1.332738 1.100074)
			(end -1.332738 1.100074)
			(stroke
				(width 0.1524)
				(type default)
			)
			(layer "F.SilkS")
		)
		(fp_line
			(start 0 -0.541274)
			(end 0.4826 -1.100074)
			(stroke
				(width 0.1524)
				(type default)
			)
			(layer "F.SilkS")
		)
		(fp_line
			(start -1.332738 -1.100074)
			(end -0.4826 -1.100074)
			(stroke
				(width 0.1524)
				(type default)
			)
			(layer "F.SilkS")
		)
		(fp_line
			(start -0.4826 -1.100074)
			(end 0 -0.541274)
			(stroke
				(width 0.1524)
				(type default)
			)
			(layer "F.SilkS")
		)
		(fp_line
			(start 0.4826 -1.100074)
			(end 1.332738 -1.100074)
			(stroke
				(width 0.1524)
				(type default)
			)
			(layer "F.SilkS")
		)
		(fp_line
			(start 1.332738 -1.100074)
			(end 1.332738 1.100074)
			(stroke
				(width 0.1524)
				(type default)
			)
			(layer "F.SilkS")
		)
		(fp_poly
			(pts
				(xy -1.72974 -1.81737) (xy -1.481582 -1.072896) (xy -2.226056 -1.321054)
			)
			(stroke
				(width 0)
				(type default)
			)
			(fill yes)
			(layer "F.SilkS")
		)
		(fp_line
			(start -0.674878 1.100074)
			(end -0.674878 -1.100074)
			(stroke
				(width 0.1)
				(type default)
			)
			(layer "F.Fab")
		)
		(fp_line
			(start 0.674878 1.100074)
			(end -0.674878 1.100074)
			(stroke
				(width 0.1)
				(type default)
			)
			(layer "F.Fab")
		)
		(fp_line
			(start -0.674878 -1.100074)
			(end 0.674878 -1.100074)
			(stroke
				(width 0.1)
				(type default)
			)
			(layer "F.Fab")
		)
		(fp_line
			(start 0.674878 -1.100074)
			(end 0.674878 1.100074)
			(stroke
				(width 0.1)
				(type default)
			)
			(layer "F.Fab")
		)
		(fp_poly
			(pts
				(xy -2.2352 -0.298958) (xy -2.2352 -1.001014) (xy -1.533144 -0.649986)
			)
			(stroke
				(width 0)
				(type default)
			)
			(fill yes)
			(layer "F.Fab")
		)
		(pad "1" smd rect
			(at -0.94996 -0.649986)
			(size 0.4318 0.508)
			(layers "F.Cu" "F.Mask" "F.Paste")
			(net "GND")
		)
		(pad "2" smd rect
			(at -0.94996 0)
			(size 0.4318 0.508)
			(layers "F.Cu" "F.Mask" "F.Paste")
			(net "BIC_MONITER")
		)
		(pad "3" smd rect
			(at -0.94996 0.649986)
			(size 0.4318 0.508)
			(layers "F.Cu" "F.Mask" "F.Paste")
			(net "BIC_MONITER_ISO")
		)
		(pad "4" smd rect
			(at 0.94996 0.649986)
			(size 0.4318 0.508)
			(layers "F.Cu" "F.Mask" "F.Paste")
			(net "GND")
		)
		(pad "5" smd rect
			(at 0.94996 0)
			(size 0.4318 0.508)
			(layers "F.Cu" "F.Mask" "F.Paste")
			(net "BIC_MONITER_N")
		)
		(pad "6" smd rect
			(at 0.94996 -0.649986)
			(size 0.4318 0.508)
			(layers "F.Cu" "F.Mask" "F.Paste")
			(net "BIC_MONITER_N")
		)
	)
	(footprint ""
		(layer "F.Cu")
		(at 49.57318 -171.473368 180)
		(property "Reference" "PR4249"
			(at 0 0 180)
			(layer "F.SilkS")
			(hide yes)
			(effects
				(font
					(size 1.27 1.27)
				)
			)
		)
		(property "Value" ""
			(at 0 0 180)
			(layer "F.Fab")
			(effects
				(font
					(size 1.27 1.27)
				)
			)
		)
		(duplicate_pad_numbers_are_jumpers no)
		(fp_line
			(start 0.7874 0.4064)
			(end -0.7874 0.4064)
			(stroke
				(width 0.1524)
				(type default)
			)
			(layer "F.SilkS")
		)
		(fp_line
			(start 0.7874 -0.4064)
			(end 0.7874 0.4064)
			(stroke
				(width 0.1524)
				(type default)
			)
			(layer "F.SilkS")
		)
		(fp_line
			(start -0.7874 0.4064)
			(end -0.7874 -0.4064)
			(stroke
				(width 0.1524)
				(type default)
			)
			(layer "F.SilkS")
		)
		(fp_line
			(start -0.7874 -0.4064)
			(end 0.7874 -0.4064)
			(stroke
				(width 0.1524)
				(type default)
			)
			(layer "F.SilkS")
		)
		(fp_line
			(start 0.67945 0.3048)
			(end 0.120396 0.3048)
			(stroke
				(width 0.1)
				(type default)
			)
			(layer "F.Fab")
		)
		(fp_line
			(start 0.67945 -0.3048)
			(end 0.67945 0.3048)
			(stroke
				(width 0.1)
				(type default)
			)
			(layer "F.Fab")
		)
		(fp_line
			(start 0.12065 -0.2794)
			(end 0.12065 -0.3048)
			(stroke
				(width 0.1)
				(type default)
			)
			(layer "F.Fab")
		)
		(fp_line
			(start 0.12065 -0.3048)
			(end 0.67945 -0.3048)
			(stroke
				(width 0.1)
				(type default)
			)
			(layer "F.Fab")
		)
		(fp_line
			(start 0.120396 0.3048)
			(end 0.120396 0.2794)
			(stroke
				(width 0.1)
				(type default)
			)
			(layer "F.Fab")
		)
		(fp_line
			(start 0.120396 0.2794)
			(end -0.12065 0.2794)
			(stroke
				(width 0.1)
				(type default)
			)
			(layer "F.Fab")
		)
		(fp_line
			(start -0.12065 0.3048)
			(end -0.67945 0.3048)
			(stroke
				(width 0.1)
				(type default)
			)
			(layer "F.Fab")
		)
		(fp_line
			(start -0.12065 0.2794)
			(end -0.12065 0.3048)
			(stroke
				(width 0.1)
				(type default)
			)
			(layer "F.Fab")
		)
		(fp_line
			(start -0.12065 -0.2794)
			(end 0.12065 -0.2794)
			(stroke
				(width 0.1)
				(type default)
			)
			(layer "F.Fab")
		)
		(fp_line
			(start -0.12065 -0.305054)
			(end -0.12065 -0.2794)
			(stroke
				(width 0.1)
				(type default)
			)
			(layer "F.Fab")
		)
		(fp_line
			(start -0.67945 0.3048)
			(end -0.67945 -0.305054)
			(stroke
				(width 0.1)
				(type default)
			)
			(layer "F.Fab")
		)
		(fp_line
			(start -0.67945 -0.305054)
			(end -0.12065 -0.305054)
			(stroke
				(width 0.1)
				(type default)
			)
			(layer "F.Fab")
		)
		(pad "1" smd circle
			(at -0.40005 0 180)
			(size 0 0)
			(layers "F.Cu" "F.Mask" "F.Paste")
			(net "PVCCFA_EHV_CPU1_FAULT")
		)
		(pad "2" smd circle
			(at 0.40005 0 180)
			(size 0 0)
			(layers "F.Cu" "F.Mask" "F.Paste")
			(net "GND")
		)
	)
)
